(kicad_pcb
	(version 20260206)
	(generator "pcbnew")
	(generator_version "10.0")
	(general
		(thickness 1.6)
		(legacy_teardrops no)
	)
	(paper "A4")
	(title_block
		(title "04192023_DAF0TMB3IC0_F0TG_MB_C_brd_V02_OCP.brd")
		(comment 1 "Grand Teton / footprints 2781-2782 of 8354")
	)
	(layers
		(0 "F.Cu" signal "TOP")
		(4 "In1.Cu" signal "GND")
		(6 "In2.Cu" signal "IN1")
		(8 "In3.Cu" signal "GND1")
		(10 "In4.Cu" signal "IN2")
		(12 "In5.Cu" signal "GND2")
		(14 "In6.Cu" signal "IN3")
		(16 "In7.Cu" signal "GND3")
		(18 "In8.Cu" signal "VCC")
		(20 "In9.Cu" signal "VCC1")
		(22 "In10.Cu" signal "GND4")
		(24 "In11.Cu" signal "IN4")
		(26 "In12.Cu" signal "GND5")
		(28 "In13.Cu" signal "IN5")
		(30 "In14.Cu" signal "GND6")
		(32 "In15.Cu" signal "IN6")
		(34 "In16.Cu" signal "GND7")
		(2 "B.Cu" signal "BOTTOM")
		(9 "F.Adhes" user "F.Adhesive")
		(11 "B.Adhes" user "B.Adhesive")
		(13 "F.Paste" user "Package Geometry/Pastemask Top")
		(15 "B.Paste" user "Package Geometry/Pastemask Bottom")
		(5 "F.SilkS" user "Ref Des/Silkscreen Top")
		(7 "B.SilkS" user "Ref Des/Silkscreen Bottom")
		(1 "F.Mask" user "Board Geometry/Soldermask Top")
		(3 "B.Mask" user "Board Geometry/Soldermask Bottom")
		(17 "Dwgs.User" user "User.Drawings")
		(19 "Cmts.User" user "User.Comments")
		(21 "Eco1.User" user "User.Eco1")
		(23 "Eco2.User" user "User.Eco2")
		(25 "Edge.Cuts" user "Board Geometry/Outline")
		(27 "Margin" user)
		(31 "F.CrtYd" user "Package Geometry/Place Bound Top")
		(29 "B.CrtYd" user "Package Geometry/Place Bound Bottom")
		(35 "F.Fab" user "Ref Des/Assembly Top")
		(33 "B.Fab" user "Ref Des/Assembly Bottom")
	)
	(footprint ""
		(layer "F.Cu")
		(at 42.637964 -172.922946 180)
		(property "Reference" "R5018"
			(at 0 0 180)
			(layer "F.SilkS")
			(hide yes)
			(effects
				(font
					(size 1.27 1.27)
				)
			)
		)
		(property "Value" ""
			(at 0 0 180)
			(layer "F.Fab")
			(effects
				(font
					(size 1.27 1.27)
				)
			)
		)
		(duplicate_pad_numbers_are_jumpers no)
		(fp_line
			(start 0.7874 0.4064)
			(end -0.7874 0.4064)
			(stroke
				(width 0.1524)
				(type default)
			)
			(layer "F.SilkS")
		)
		(fp_line
			(start 0.7874 -0.4064)
			(end 0.7874 0.4064)
			(stroke
				(width 0.1524)
				(type default)
			)
			(layer "F.SilkS")
		)
		(fp_line
			(start -0.7874 0.4064)
			(end -0.7874 -0.4064)
			(stroke
				(width 0.1524)
				(type default)
			)
			(layer "F.SilkS")
		)
		(fp_line
			(start -0.7874 -0.4064)
			(end 0.7874 -0.4064)
			(stroke
				(width 0.1524)
				(type default)
			)
			(layer "F.SilkS")
		)
		(fp_line
			(start 0.67945 0.3048)
			(end 0.120396 0.3048)
			(stroke
				(width 0.1)
				(type default)
			)
			(layer "F.Fab")
		)
		(fp_line
			(start 0.67945 -0.3048)
			(end 0.67945 0.3048)
			(stroke
				(width 0.1)
				(type default)
			)
			(layer "F.Fab")
		)
		(fp_line
			(start 0.12065 -0.2794)
			(end 0.12065 -0.3048)
			(stroke
				(width 0.1)
				(type default)
			)
			(layer "F.Fab")
		)
		(fp_line
			(start 0.12065 -0.3048)
			(end 0.67945 -0.3048)
			(stroke
				(width 0.1)
				(type default)
			)
			(layer "F.Fab")
		)
		(fp_line
			(start 0.120396 0.3048)
			(end 0.120396 0.2794)
			(stroke
				(width 0.1)
				(type default)
			)
			(layer "F.Fab")
		)
		(fp_line
			(start 0.120396 0.2794)
			(end -0.12065 0.2794)
			(stroke
				(width 0.1)
				(type default)
			)
			(layer "F.Fab")
		)
		(fp_line
			(start -0.12065 0.3048)
			(end -0.67945 0.3048)
			(stroke
				(width 0.1)
				(type default)
			)
			(layer "F.Fab")
		)
		(fp_line
			(start -0.12065 0.2794)
			(end -0.12065 0.3048)
			(stroke
				(width 0.1)
				(type default)
			)
			(layer "F.Fab")
		)
		(fp_line
			(start -0.12065 -0.2794)
			(end 0.12065 -0.2794)
			(stroke
				(width 0.1)
				(type default)
			)
			(layer "F.Fab")
		)
		(fp_line
			(start -0.12065 -0.305054)
			(end -0.12065 -0.2794)
			(stroke
				(width 0.1)
				(type default)
			)
			(layer "F.Fab")
		)
		(fp_line
			(start -0.67945 0.3048)
			(end -0.67945 -0.305054)
			(stroke
				(width 0.1)
				(type default)
			)
			(layer "F.Fab")
		)
		(fp_line
			(start -0.67945 -0.305054)
			(end -0.12065 -0.305054)
			(stroke
				(width 0.1)
				(type default)
			)
			(layer "F.Fab")
		)
		(pad "1" smd circle
			(at -0.40005 0 180)
			(size 0 0)
			(layers "F.Cu" "F.Mask" "F.Paste")
			(net "PVDD11_S3_P1")
		)
		(pad "2" smd circle
			(at 0.40005 0 180)
			(size 0 0)
			(layers "F.Cu" "F.Mask" "F.Paste")
			(net "I3C_SCM_2_R_SCL")
		)
	)
	(footprint ""
		(layer "F.Cu")
		(at 249.765312 -54.440582 -90)
		(property "Reference" "PR3957"
			(at 0 0 270)
			(layer "F.SilkS")
			(hide yes)
			(effects
				(font
					(size 1.27 1.27)
				)
			)
		)
		(property "Value" ""
			(at 0 0 270)
			(layer "F.Fab")
			(effects
				(font
					(size 1.27 1.27)
				)
			)
		)
		(duplicate_pad_numbers_are_jumpers no)
		(fp_line
			(start -1.2954 0.5842)
			(end -1.2954 -0.5842)
			(stroke
				(width 0.1524)
				(type default)
			)
			(layer "F.SilkS")
		)
		(fp_line
			(start 1.2954 0.5842)
			(end -1.2954 0.5842)
			(stroke
				(width 0.1524)
				(type default)
			)
			(layer "F.SilkS")
		)
		(fp_line
			(start -1.2954 -0.5842)
			(end 1.2954 -0.5842)
			(stroke
				(width 0.1524)
				(type default)
			)
			(layer "F.SilkS")
		)
		(fp_line
			(start 1.2954 -0.5842)
			(end 1.2954 0.5842)
			(stroke
				(width 0.1524)
				(type default)
			)
			(layer "F.SilkS")
		)
		(fp_line
			(start -0.8636 0.4572)
			(end -0.8636 0.4318)
			(stroke
				(width 0.1)
				(type default)
			)
			(layer "F.Fab")
		)
		(fp_line
			(start 0.8636 0.4572)
			(end -0.8636 0.4572)
			(stroke
				(width 0.1)
				(type default)
			)
			(layer "F.Fab")
		)
		(fp_line
			(start -0.8636 0.4318)
			(end -0.8636 0.4064)
			(stroke
				(width 0.1)
				(type default)
			)
			(layer "F.Fab")
		)
		(fp_line
			(start -1.1938 0.4064)
			(end -1.1938 -0.406654)
			(stroke
				(width 0.1)
				(type default)
			)
			(layer "F.Fab")
		)
		(fp_line
			(start -0.8636 0.4064)
			(end -1.1938 0.4064)
			(stroke
				(width 0.1)
				(type default)
			)
			(layer "F.Fab")
		)
		(fp_line
			(start 0.8636 0.4064)
			(end 0.8636 0.4572)
			(stroke
				(width 0.1)
				(type default)
			)
			(layer "F.Fab")
		)
		(fp_line
			(start 1.1938 0.4064)
			(end 0.8636 0.4064)
			(stroke
				(width 0.1)
				(type default)
			)
			(layer "F.Fab")
		)
		(fp_line
			(start -1.1938 -0.406654)
			(end -0.8636 -0.406654)
			(stroke
				(width 0.1)
				(type default)
			)
			(layer "F.Fab")
		)
		(fp_line
			(start -0.8636 -0.406654)
			(end -0.8636 -0.4572)
			(stroke
				(width 0.1)
				(type default)
			)
			(layer "F.Fab")
		)
		(fp_line
			(start 0.8636 -0.406654)
			(end 1.1938 -0.406654)
			(stroke
				(width 0.1)
				(type default)
			)
			(layer "F.Fab")
		)
		(fp_line
			(start 1.1938 -0.406654)
			(end 1.1938 0.4064)
			(stroke
				(width 0.1)
				(type default)
			)
			(layer "F.Fab")
		)
		(fp_line
			(start -0.8636 -0.4572)
			(end 0.8636 -0.4572)
			(stroke
				(width 0.1)
				(type default)
			)
			(layer "F.Fab")
		)
		(fp_line
			(start 0.8636 -0.4572)
			(end 0.8636 -0.406654)
			(stroke
				(width 0.1)
				(type default)
			)
			(layer "F.Fab")
		)
		(pad "1" smd rect
			(at -0.7366 0 180)
			(size 0.7112 0.8128)
			(layers "F.Cu" "F.Mask" "F.Paste")
			(net "P12V_AUX")
		)
		(pad "2" smd rect
			(at 0.7366 0 180)
			(size 0.7112 0.8128)
			(layers "F.Cu" "F.Mask" "F.Paste")
			(net "P12V_E1S_AVIN_PD_0")
		)
	)
)
